(kicad_pcb
	(version 20260206)
	(generator "pcbnew")
	(generator_version "10.0")
	(general
		(thickness 1.5755)
		(legacy_teardrops no)
	)
	(paper "A4")
	(title_block
		(title "gnss-rcb-f9t — GPS_MODULE_ZED-F9T.PcbDoc")
		(comment 1 "Time Appliance Project (Time Card) / footprints 31-39 of 44")
	)
	(layers
		(0 "F.Cu" signal "Top Layer")
		(4 "In1.Cu" signal "Int1 (GND)")
		(6 "In2.Cu" signal "Int2 (GND)")
		(2 "B.Cu" signal "Bottom Layer")
		(9 "F.Adhes" user "F.Adhesive")
		(11 "B.Adhes" user "B.Adhesive")
		(13 "F.Paste" user "Top Paste")
		(15 "B.Paste" user "Bottom Paste")
		(5 "F.SilkS" user "Top Overlay")
		(7 "B.SilkS" user "Bottom Overlay")
		(1 "F.Mask" user "Top Solder")
		(3 "B.Mask" user "Bottom Solder")
		(17 "Dwgs.User" user "User.Drawings")
		(19 "Cmts.User" user "User.Comments")
		(21 "Eco1.User" user "User.Eco1")
		(23 "Eco2.User" user "User.Eco2")
		(25 "Edge.Cuts" user)
		(27 "Margin" user)
		(31 "F.CrtYd" user "Top Courtyard")
		(29 "B.CrtYd" user "Bottom Courtyard")
		(35 "F.Fab" user "Top Component Outline")
		(33 "B.Fab" user "Bottom Component Outline")
	)
	(footprint "Vault:FP-RMCF0402-IPC_C"
		(layer "F.Cu")
		(at 170.7443 107.7951 -90)
		(property "Reference" "R5"
			(at -1.755 0.02827 270)
			(unlocked yes)
			(layer "F.SilkS")
			(effects
				(font
					(size 0.8 0.8)
					(thickness 0.15)
				)
			)
		)
		(property "Value" "10k"
			(at 2.632122 -15.323605 0)
			(unlocked yes)
			(layer "F.SilkS")
			(hide yes)
			(effects
				(font
					(size 1.524 1.524)
					(thickness 0.254)
				)
			)
		)
		(sheetname "ZED-F9T")
		(sheetfile "ZED-F9T.kicad_sch")
		(duplicate_pad_numbers_are_jumpers no)
		(fp_line
			(start 0.65607 0.675)
			(end -0.65607 0.675)
			(stroke
				(width 0.2)
				(type solid)
			)
			(layer "F.SilkS")
		)
		(fp_line
			(start 0.65607 -0.675)
			(end -0.65607 -0.675)
			(stroke
				(width 0.2)
				(type solid)
			)
			(layer "F.SilkS")
		)
		(fp_line
			(start -0.75607 0.375)
			(end -0.75607 -0.375)
			(stroke
				(width 0.2)
				(type solid)
			)
			(layer "F.CrtYd")
		)
		(fp_line
			(start 0.75607 0.375)
			(end -0.75607 0.375)
			(stroke
				(width 0.2)
				(type solid)
			)
			(layer "F.CrtYd")
		)
		(fp_line
			(start 0.75607 0.375)
			(end 0.75607 -0.375)
			(stroke
				(width 0.2)
				(type solid)
			)
			(layer "F.CrtYd")
		)
		(fp_line
			(start 0.75607 -0.375)
			(end -0.75607 -0.375)
			(stroke
				(width 0.2)
				(type solid)
			)
			(layer "F.CrtYd")
		)
		(fp_line
			(start 0 0.5)
			(end 0 -0.5)
			(stroke
				(width 0.1)
				(type solid)
			)
			(layer "F.Fab")
		)
		(fp_line
			(start -0.75607 0.375)
			(end -0.75607 -0.375)
			(stroke
				(width 0.2)
				(type solid)
			)
			(layer "F.Fab")
		)
		(fp_line
			(start 0.75607 0.375)
			(end -0.75607 0.375)
			(stroke
				(width 0.2)
				(type solid)
			)
			(layer "F.Fab")
		)
		(fp_line
			(start 0.75607 0.375)
			(end 0.75607 -0.375)
			(stroke
				(width 0.2)
				(type solid)
			)
			(layer "F.Fab")
		)
		(fp_line
			(start 0.5 0)
			(end -0.5 0)
			(stroke
				(width 0.1)
				(type solid)
			)
			(layer "F.Fab")
		)
		(fp_line
			(start 0.75607 -0.375)
			(end -0.75607 -0.375)
			(stroke
				(width 0.2)
				(type solid)
			)
			(layer "F.Fab")
		)
		(fp_text user "${REFERENCE}"
			(at -0.00001 0.09647 270)
			(unlocked yes)
			(layer "F.Fab")
			(effects
				(font
					(face "Arial")
					(size 0.63 0.63)
					(thickness 0.1)
				)
				(justify left bottom)
			)
		)
		(pad "1" smd rect
			(at -0.36554 0 270)
			(size 0.58106 0.47247)
			(layers "F.Cu" "F.Mask" "F.Paste")
			(net "RXD")
			(solder_mask_margin 0)
			(solder_paste_margin 0)
		)
		(pad "2" smd rect
			(at 0.36554 0 270)
			(size 0.58106 0.47247)
			(layers "F.Cu" "F.Mask" "F.Paste")
			(net "RXD_IN")
			(solder_mask_margin 0)
			(solder_paste_margin 0)
		)
	)
	(footprint "Vault:FP-RMCF0402-MFG"
		(layer "F.Cu")
		(at 130.5361 109.1921 180)
		(property "Reference" "R10"
			(at -0.022995 -1.52687 0)
			(unlocked yes)
			(layer "F.SilkS")
			(effects
				(font
					(size 0.8 0.8)
					(thickness 0.15)
				)
			)
		)
		(property "Value" "1k"
			(at -0.57117 -2.378202 0)
			(unlocked yes)
			(layer "F.SilkS")
			(hide yes)
			(effects
				(font
					(size 1.524 1.524)
					(thickness 0.254)
				)
			)
		)
		(sheetname "Antenna_Supervisor")
		(sheetfile "Antenna_Supervisor.kicad_sch")
		(duplicate_pad_numbers_are_jumpers no)
		(fp_line
			(start 0.55 0.7)
			(end -0.55 0.7)
			(stroke
				(width 0.2)
				(type solid)
			)
			(layer "F.SilkS")
		)
		(fp_line
			(start 0.55 -0.7)
			(end -0.55 -0.7)
			(stroke
				(width 0.2)
				(type solid)
			)
			(layer "F.SilkS")
		)
		(fp_line
			(start 0.85 0.4)
			(end -0.85 0.4)
			(stroke
				(width 0.2)
				(type solid)
			)
			(layer "F.CrtYd")
		)
		(fp_line
			(start 0.85 -0.4)
			(end 0.85 0.4)
			(stroke
				(width 0.2)
				(type solid)
			)
			(layer "F.CrtYd")
		)
		(fp_line
			(start 0.85 -0.4)
			(end -0.85 -0.4)
			(stroke
				(width 0.2)
				(type solid)
			)
			(layer "F.CrtYd")
		)
		(fp_line
			(start -0.85 -0.4)
			(end -0.85 0.4)
			(stroke
				(width 0.2)
				(type solid)
			)
			(layer "F.CrtYd")
		)
		(fp_line
			(start 0.85 0.4)
			(end -0.85 0.4)
			(stroke
				(width 0.2)
				(type solid)
			)
			(layer "F.Fab")
		)
		(fp_line
			(start 0.85 -0.4)
			(end 0.85 0.4)
			(stroke
				(width 0.2)
				(type solid)
			)
			(layer "F.Fab")
		)
		(fp_line
			(start 0.85 -0.4)
			(end -0.85 -0.4)
			(stroke
				(width 0.2)
				(type solid)
			)
			(layer "F.Fab")
		)
		(fp_line
			(start 0.5 0)
			(end -0.5 0)
			(stroke
				(width 0.1)
				(type solid)
			)
			(layer "F.Fab")
		)
		(fp_line
			(start 0 -0.5)
			(end 0 0.5)
			(stroke
				(width 0.1)
				(type solid)
			)
			(layer "F.Fab")
		)
		(fp_line
			(start -0.85 -0.4)
			(end -0.85 0.4)
			(stroke
				(width 0.2)
				(type solid)
			)
			(layer "F.Fab")
		)
		(fp_text user "${REFERENCE}"
			(at 0.6604 -1.87447 360)
			(unlocked yes)
			(layer "F.Fab")
			(effects
				(font
					(face "Arial")
					(size 0.63 0.63)
					(thickness 0.1)
				)
				(justify left bottom)
			)
		)
		(pad "1" smd rect
			(at -0.5 0 180)
			(size 0.5 0.6)
			(layers "F.Cu" "F.Mask" "F.Paste")
			(net "NetR10_1")
			(solder_mask_margin 0)
			(solder_paste_margin 0)
		)
		(pad "2" smd rect
			(at 0.5 0 180)
			(size 0.5 0.6)
			(layers "F.Cu" "F.Mask" "F.Paste")
			(net "NetQ1_3")
			(solder_mask_margin 0)
			(solder_paste_margin 0)
		)
	)
	(footprint "Vault:FP-RMCF0402-MFG"
		(layer "F.Cu")
		(at 148.8241 94.8411 90)
		(property "Reference" "R1"
			(at 2.055 0.15527 90)
			(unlocked yes)
			(layer "F.SilkS")
			(effects
				(font
					(size 0.8 0.8)
					(thickness 0.15)
				)
			)
		)
		(property "Value" "1k"
			(at -2.378202 0.57117 0)
			(unlocked yes)
			(layer "F.SilkS")
			(hide yes)
			(effects
				(font
					(size 1.524 1.524)
					(thickness 0.254)
				)
			)
		)
		(sheetname "ZED-F9T")
		(sheetfile "ZED-F9T.kicad_sch")
		(duplicate_pad_numbers_are_jumpers no)
		(fp_line
			(start -0.55 -0.7)
			(end 0.55 -0.7)
			(stroke
				(width 0.2)
				(type solid)
			)
			(layer "F.SilkS")
		)
		(fp_line
			(start -0.55 0.7)
			(end 0.55 0.7)
			(stroke
				(width 0.2)
				(type solid)
			)
			(layer "F.SilkS")
		)
		(fp_line
			(start 0.85 -0.4)
			(end 0.85 0.4)
			(stroke
				(width 0.2)
				(type solid)
			)
			(layer "F.CrtYd")
		)
		(fp_line
			(start -0.85 -0.4)
			(end 0.85 -0.4)
			(stroke
				(width 0.2)
				(type solid)
			)
			(layer "F.CrtYd")
		)
		(fp_line
			(start -0.85 -0.4)
			(end -0.85 0.4)
			(stroke
				(width 0.2)
				(type solid)
			)
			(layer "F.CrtYd")
		)
		(fp_line
			(start -0.85 0.4)
			(end 0.85 0.4)
			(stroke
				(width 0.2)
				(type solid)
			)
			(layer "F.CrtYd")
		)
		(fp_line
			(start 0 -0.5)
			(end 0 0.5)
			(stroke
				(width 0.1)
				(type solid)
			)
			(layer "F.Fab")
		)
		(fp_line
			(start 0.85 -0.4)
			(end 0.85 0.4)
			(stroke
				(width 0.2)
				(type solid)
			)
			(layer "F.Fab")
		)
		(fp_line
			(start -0.85 -0.4)
			(end 0.85 -0.4)
			(stroke
				(width 0.2)
				(type solid)
			)
			(layer "F.Fab")
		)
		(fp_line
			(start -0.85 -0.4)
			(end -0.85 0.4)
			(stroke
				(width 0.2)
				(type solid)
			)
			(layer "F.Fab")
		)
		(fp_line
			(start -0.5 0)
			(end 0.5 0)
			(stroke
				(width 0.1)
				(type solid)
			)
			(layer "F.Fab")
		)
		(fp_line
			(start -0.85 0.4)
			(end 0.85 0.4)
			(stroke
				(width 0.2)
				(type solid)
			)
			(layer "F.Fab")
		)
		(fp_text user "${REFERENCE}"
			(at -0.00001 0.10711 90)
			(unlocked yes)
			(layer "F.Fab")
			(effects
				(font
					(face "Arial")
					(size 0.63 0.63)
					(thickness 0.1)
				)
				(justify left bottom)
			)
		)
		(pad "1" smd rect
			(at -0.5 0 90)
			(size 0.5 0.6)
			(layers "F.Cu" "F.Mask" "F.Paste")
			(net "NetC5_1")
			(solder_mask_margin 0)
			(solder_paste_margin 0)
		)
		(pad "2" smd rect
			(at 0.5 0 90)
			(size 0.5 0.6)
			(layers "F.Cu" "F.Mask" "F.Paste")
			(net "VCC")
			(solder_mask_margin 0)
			(solder_paste_margin 0)
		)
	)
	(footprint "Vault:FP-LQG15HH_02-IPC_B"
		(layer "F.Cu")
		(at 127.9961 101.6991 90)
		(property "Reference" "L1"
			(at 1.87673 0.15 0)
			(unlocked yes)
			(layer "F.SilkS")
			(effects
				(font
					(size 0.8 0.8)
					(thickness 0.15)
				)
			)
		)
		(property "Value" "47nH 300mA"
			(at -2.352802 6.23332 0)
			(unlocked yes)
			(layer "F.SilkS")
			(hide yes)
			(effects
				(font
					(size 1.524 1.524)
					(thickness 0.254)
				)
			)
		)
		(sheetname "Antenna_Supervisor")
		(sheetfile "Antenna_Supervisor.kicad_sch")
		(duplicate_pad_numbers_are_jumpers no)
		(fp_line
			(start -0.73624 -0.68623)
			(end 0.73624 -0.68623)
			(stroke
				(width 0.2)
				(type solid)
			)
			(layer "F.SilkS")
		)
		(fp_line
			(start -0.73624 0.68624)
			(end 0.73624 0.68624)
			(stroke
				(width 0.2)
				(type solid)
			)
			(layer "F.SilkS")
		)
		(fp_circle
			(center -1.38624 0)
			(end -1.26124 0)
			(stroke
				(width 0.25)
				(type solid)
			)
			(fill no)
			(layer "F.SilkS")
		)
		(fp_line
			(start 0.88624 -0.43624)
			(end 0.88624 0.43624)
			(stroke
				(width 0.2)
				(type solid)
			)
			(layer "F.CrtYd")
		)
		(fp_line
			(start -0.88624 -0.43624)
			(end 0.88624 -0.43624)
			(stroke
				(width 0.2)
				(type solid)
			)
			(layer "F.CrtYd")
		)
		(fp_line
			(start -0.88624 -0.43624)
			(end -0.88624 0.43624)
			(stroke
				(width 0.2)
				(type solid)
			)
			(layer "F.CrtYd")
		)
		(fp_line
			(start -0.88624 0.43624)
			(end 0.88624 0.43624)
			(stroke
				(width 0.2)
				(type solid)
			)
			(layer "F.CrtYd")
		)
		(fp_line
			(start 0 -0.5)
			(end 0 0.5)
			(stroke
				(width 0.1)
				(type solid)
			)
			(layer "F.Fab")
		)
		(fp_line
			(start 0.88624 -0.43624)
			(end 0.88624 0.43624)
			(stroke
				(width 0.2)
				(type solid)
			)
			(layer "F.Fab")
		)
		(fp_line
			(start -0.88624 -0.43624)
			(end 0.88624 -0.43624)
			(stroke
				(width 0.2)
				(type solid)
			)
			(layer "F.Fab")
		)
		(fp_line
			(start -0.88624 -0.43624)
			(end -0.88624 0.43624)
			(stroke
				(width 0.2)
				(type solid)
			)
			(layer "F.Fab")
		)
		(fp_line
			(start -0.5 0)
			(end 0.5 0)
			(stroke
				(width 0.1)
				(type solid)
			)
			(layer "F.Fab")
		)
		(fp_line
			(start -0.88624 0.43624)
			(end 0.88624 0.43624)
			(stroke
				(width 0.2)
				(type solid)
			)
			(layer "F.Fab")
		)
		(fp_text user "${REFERENCE}"
			(at -0.1016 1.5295 90)
			(unlocked yes)
			(layer "F.Fab")
			(effects
				(font
					(face "Arial")
					(size 0.63 0.63)
					(thickness 0.1)
				)
				(justify left bottom)
			)
		)
		(pad "1" smd rect
			(at -0.42856 0 90)
			(size 0.61535 0.57247)
			(layers "F.Cu" "F.Mask" "F.Paste")
			(net "NetC10_1")
			(solder_mask_margin 0)
			(solder_paste_margin 0)
		)
		(pad "2" smd rect
			(at 0.42857 0 90)
			(size 0.61535 0.57247)
			(layers "F.Cu" "F.Mask" "F.Paste")
			(net "RF_ANT")
			(solder_mask_margin 0)
			(solder_paste_margin 0)
		)
	)
	(footprint "Vault:TP001V_SMT_100DIA"
		(layer "F.Cu")
		(at 141.7121 95.0951 90)
		(property "Reference" "TP3"
			(at 2.436 -0.02253 90)
			(unlocked yes)
			(layer "F.SilkS")
			(effects
				(font
					(size 0.8 0.8)
					(thickness 0.15)
				)
			)
		)
		(property "Value" "SMT_100DIA"
			(at -2.124202 7.0716 0)
			(unlocked yes)
			(layer "F.SilkS")
			(hide yes)
			(effects
				(font
					(size 1.524 1.524)
					(thickness 0.254)
				)
			)
		)
		(sheetname "ZED-F9T")
		(sheetfile "ZED-F9T.kicad_sch")
		(duplicate_pad_numbers_are_jumpers no)
		(pad "1" smd circle
			(at 0 0 90)
			(size 1 1)
			(layers "F.Cu" "F.Mask" "F.Paste")
			(net "NetTP3_1")
			(solder_mask_margin 0.05)
			(solder_paste_margin 0)
			(thermal_bridge_angle 90)
		)
	)
	(footprint "Vault:TP001V_SMT_100DIA"
		(layer "F.Cu")
		(at 144.5061 95.0951 90)
		(property "Reference" "TP1"
			(at 2.436 0.30767 90)
			(unlocked yes)
			(layer "F.SilkS")
			(effects
				(font
					(size 0.8 0.8)
					(thickness 0.15)
				)
			)
		)
		(property "Value" "SMT_100DIA"
			(at -2.124202 7.0716 0)
			(unlocked yes)
			(layer "F.SilkS")
			(hide yes)
			(effects
				(font
					(size 1.524 1.524)
					(thickness 0.254)
				)
			)
		)
		(sheetname "ZED-F9T")
		(sheetfile "ZED-F9T.kicad_sch")
		(duplicate_pad_numbers_are_jumpers no)
		(pad "1" smd circle
			(at 0 0 90)
			(size 1 1)
			(layers "F.Cu" "F.Mask" "F.Paste")
			(net "NetTP1_1")
			(solder_mask_margin 0.05)
			(solder_paste_margin 0)
			(thermal_bridge_angle 90)
		)
	)
	(footprint "Vault:TP001V_SMT_100DIA"
		(layer "F.Cu")
		(at 143.1091 95.0951 90)
		(property "Reference" "TP2"
			(at 2.6138 0.02827 90)
			(unlocked yes)
			(layer "F.SilkS")
			(effects
				(font
					(size 0.8 0.8)
					(thickness 0.15)
				)
			)
		)
		(property "Value" "SMT_100DIA"
			(at -2.124202 7.0716 0)
			(unlocked yes)
			(layer "F.SilkS")
			(hide yes)
			(effects
				(font
					(size 1.524 1.524)
					(thickness 0.254)
				)
			)
		)
		(sheetname "ZED-F9T")
		(sheetfile "ZED-F9T.kicad_sch")
		(duplicate_pad_numbers_are_jumpers no)
		(pad "1" smd circle
			(at 0 0 90)
			(size 1 1)
			(layers "F.Cu" "F.Mask" "F.Paste")
			(net "NetTP2_1")
			(solder_mask_margin 0.05)
			(solder_paste_margin 0)
			(thermal_bridge_angle 90)
		)
	)
	(footprint "Vault:FP-RMCF0402-IPC_C"
		(layer "F.Cu")
		(at 168.6615 107.7951 90)
		(property "Reference" "R6"
			(at 1.755 -0.02827 270)
			(unlocked yes)
			(layer "F.SilkS")
			(effects
				(font
					(size 0.8 0.8)
					(thickness 0.15)
				)
			)
		)
		(property "Value" "10k"
			(at -2.632122 15.323605 0)
			(unlocked yes)
			(layer "F.SilkS")
			(hide yes)
			(effects
				(font
					(size 1.524 1.524)
					(thickness 0.254)
				)
			)
		)
		(sheetname "ZED-F9T")
		(sheetfile "ZED-F9T.kicad_sch")
		(duplicate_pad_numbers_are_jumpers no)
		(fp_line
			(start -0.65607 -0.675)
			(end 0.65607 -0.675)
			(stroke
				(width 0.2)
				(type solid)
			)
			(layer "F.SilkS")
		)
		(fp_line
			(start -0.65607 0.675)
			(end 0.65607 0.675)
			(stroke
				(width 0.2)
				(type solid)
			)
			(layer "F.SilkS")
		)
		(fp_line
			(start 0.75607 -0.375)
			(end 0.75607 0.375)
			(stroke
				(width 0.2)
				(type solid)
			)
			(layer "F.CrtYd")
		)
		(fp_line
			(start -0.75607 -0.375)
			(end 0.75607 -0.375)
			(stroke
				(width 0.2)
				(type solid)
			)
			(layer "F.CrtYd")
		)
		(fp_line
			(start -0.75607 -0.375)
			(end -0.75607 0.375)
			(stroke
				(width 0.2)
				(type solid)
			)
			(layer "F.CrtYd")
		)
		(fp_line
			(start -0.75607 0.375)
			(end 0.75607 0.375)
			(stroke
				(width 0.2)
				(type solid)
			)
			(layer "F.CrtYd")
		)
		(fp_line
			(start 0 -0.5)
			(end 0 0.5)
			(stroke
				(width 0.1)
				(type solid)
			)
			(layer "F.Fab")
		)
		(fp_line
			(start 0.75607 -0.375)
			(end 0.75607 0.375)
			(stroke
				(width 0.2)
				(type solid)
			)
			(layer "F.Fab")
		)
		(fp_line
			(start -0.75607 -0.375)
			(end 0.75607 -0.375)
			(stroke
				(width 0.2)
				(type solid)
			)
			(layer "F.Fab")
		)
		(fp_line
			(start -0.75607 -0.375)
			(end -0.75607 0.375)
			(stroke
				(width 0.2)
				(type solid)
			)
			(layer "F.Fab")
		)
		(fp_line
			(start -0.5 0)
			(end 0.5 0)
			(stroke
				(width 0.1)
				(type solid)
			)
			(layer "F.Fab")
		)
		(fp_line
			(start -0.75607 0.375)
			(end 0.75607 0.375)
			(stroke
				(width 0.2)
				(type solid)
			)
			(layer "F.Fab")
		)
		(fp_text user "${REFERENCE}"
			(at -0.00001 0.09647 90)
			(unlocked yes)
			(layer "F.Fab")
			(effects
				(font
					(face "Arial")
					(size 0.63 0.63)
					(thickness 0.1)
				)
				(justify left bottom)
			)
		)
		(pad "1" smd rect
			(at -0.36554 0 90)
			(size 0.58106 0.47247)
			(layers "F.Cu" "F.Mask" "F.Paste")
			(net "TXD_OUT")
			(solder_mask_margin 0)
			(solder_paste_margin 0)
		)
		(pad "2" smd rect
			(at 0.36554 0 90)
			(size 0.58106 0.47247)
			(layers "F.Cu" "F.Mask" "F.Paste")
			(net "TXD")
			(solder_mask_margin 0)
			(solder_paste_margin 0)
		)
	)
	(footprint "Vault:TP001V_SMT_100DIA"
		(layer "F.Cu")
		(at 150.6021 95.0951 90)
		(property "Reference" "TP5"
			(at 2.6138 0.12987 90)
			(unlocked yes)
			(layer "F.SilkS")
			(effects
				(font
					(size 0.8 0.8)
					(thickness 0.15)
				)
			)
		)
		(property "Value" "SMT_100DIA"
			(at -2.124202 7.0716 0)
			(unlocked yes)
			(layer "F.SilkS")
			(hide yes)
			(effects
				(font
					(size 1.524 1.524)
					(thickness 0.254)
				)
			)
		)
		(sheetname "ZED-F9T")
		(sheetfile "ZED-F9T.kicad_sch")
		(duplicate_pad_numbers_are_jumpers no)
		(pad "1" smd circle
			(at 0 0 90)
			(size 1 1)
			(layers "F.Cu" "F.Mask" "F.Paste")
			(net "NetTP5_1")
			(solder_mask_margin 0.05)
			(solder_paste_margin 0)
			(thermal_bridge_angle 90)
		)
	)
)
